G04 ================== begin FILE IDENTIFICATION RECORD ==================*
G04 Layout Name:  16368-sb.brd*
G04 Film Name:    TSMD*
G04 File Format:  Gerber RS274X*
G04 File Origin:  Cadence Allegro 16.5-S056*
G04 Origin Date:  Tue Feb 07 09:07:41 2017*
G04 *
G04 Layer:  VIA CLASS/PASTEMASK_TOP*
G04 Layer:  PIN/PASTEMASK_TOP*
G04 Layer:  PACKAGE GEOMETRY/PASTEMASK_TOP*
G04 Layer:  DRAWING FORMAT/LAYER_PCB_STORY*
G04 Layer:  DRAWING FORMAT/LAYER_PAST_T*
G04 Layer:  BOARD GEOMETRY/PANEL_OUTLINE*
G04 *
G04 Offset:    (0.00 0.00)*
G04 Mirror:    No*
G04 Mode:      Positive*
G04 Rotation:  0*
G04 FullContactRelief:  No*
G04 UndefLineWidth:     6.00*
G04 ================== end FILE IDENTIFICATION RECORD ====================*
%FSLAX35Y35*MOIN*%
%IR0*IPPOS*OFA0.00000B0.00000*MIA0B0*SFA1.00000B1.00000*%
%AMMACRO12*
21,1,.041,.02,0.0,0.0,141.*%
%ADD12MACRO12*%
%ADD10C,.04*%
%ADD23C,.026*%
%ADD11C,.086*%
%AMMACRO30*
4,1,40,.011,-.007,
.011,.007,
.010939,.007695,
.010759,.008368,
.010464,.009,
.010064,.009571,
.009571,.010064,
.009,.010464,
.008368,.010759,
.007695,.010939,
.007,.011,
-.007,.011,
-.007695,.010939,
-.008368,.010759,
-.009,.010464,
-.009571,.010064,
-.010064,.009571,
-.010464,.009,
-.010759,.008368,
-.010939,.007695,
-.011,.007,
-.011,-.007,
-.010939,-.007695,
-.010759,-.008368,
-.010464,-.009,
-.010064,-.009571,
-.009571,-.010064,
-.009,-.010464,
-.008368,-.010759,
-.007695,-.010939,
-.007,-.011,
.007,-.011,
.007695,-.010939,
.008368,-.010759,
.009,-.010464,
.009571,-.010064,
.010064,-.009571,
.010464,-.009,
.010759,-.008368,
.010939,-.007695,
.011,-.007,
0.0*
%
%ADD30MACRO30*%
%AMMACRO18*
4,1,40,.007,.011,
-.007,.011,
-.007695,.010939,
-.008368,.010759,
-.009,.010464,
-.009571,.010064,
-.010064,.009571,
-.010464,.009,
-.010759,.008368,
-.010939,.007695,
-.011,.007,
-.011,-.007,
-.010939,-.007695,
-.010759,-.008368,
-.010464,-.009,
-.010064,-.009571,
-.009571,-.010064,
-.009,-.010464,
-.008368,-.010759,
-.007695,-.010939,
-.007,-.011,
.007,-.011,
.007695,-.010939,
.008368,-.010759,
.009,-.010464,
.009571,-.010064,
.010064,-.009571,
.010464,-.009,
.010759,-.008368,
.010939,-.007695,
.011,-.007,
.011,.007,
.010939,.007695,
.010759,.008368,
.010464,.009,
.010064,.009571,
.009571,.010064,
.009,.010464,
.008368,.010759,
.007695,.010939,
.007,.011,
0.0*
%
%ADD18MACRO18*%
%AMMACRO31*
4,1,40,.011,-.007,
.011,.007,
.010939,.007695,
.010759,.008368,
.010464,.009,
.010064,.009571,
.009571,.010064,
.009,.010464,
.008368,.010759,
.007695,.010939,
.007,.011,
-.007,.011,
-.007695,.010939,
-.008368,.010759,
-.009,.010464,
-.009571,.010064,
-.010064,.009571,
-.010464,.009,
-.010759,.008368,
-.010939,.007695,
-.011,.007,
-.011,-.007,
-.010939,-.007695,
-.010759,-.008368,
-.010464,-.009,
-.010064,-.009571,
-.009571,-.010064,
-.009,-.010464,
-.008368,-.010759,
-.007695,-.010939,
-.007,-.011,
.007,-.011,
.007695,-.010939,
.008368,-.010759,
.009,-.010464,
.009571,-.010064,
.010064,-.009571,
.010464,-.009,
.010759,-.008368,
.010939,-.007695,
.011,-.007,
0.0*
%
%ADD31MACRO31*%
%AMMACRO19*
4,1,40,.007,.011,
-.007,.011,
-.007695,.010939,
-.008368,.010759,
-.009,.010464,
-.009571,.010064,
-.010064,.009571,
-.010464,.009,
-.010759,.008368,
-.010939,.007695,
-.011,.007,
-.011,-.007,
-.010939,-.007695,
-.010759,-.008368,
-.010464,-.009,
-.010064,-.009571,
-.009571,-.010064,
-.009,-.010464,
-.008368,-.010759,
-.007695,-.010939,
-.007,-.011,
.007,-.011,
.007695,-.010939,
.008368,-.010759,
.009,-.010464,
.009571,-.010064,
.010064,-.009571,
.010464,-.009,
.010759,-.008368,
.010939,-.007695,
.011,-.007,
.011,.007,
.010939,.007695,
.010759,.008368,
.010464,.009,
.010064,.009571,
.009571,.010064,
.009,.010464,
.008368,.010759,
.007695,.010939,
.007,.011,
0.0*
%
%ADD19MACRO19*%
%ADD27R,.04X.022*%
%ADD24R,.032X.022*%
%ADD14R,.012X.033*%
%AMMACRO13*
21,1,.041,.02,0.0,0.0,39.*%
%ADD13MACRO13*%
%ADD21R,.048X.016*%
%ADD22R,.016X.048*%
%ADD26R,.063X.038*%
%ADD20R,.073X.049*%
%AMMACRO29*
4,1,40,-.008,-.012,
.008,-.012,
.008695,-.011939,
.009368,-.011759,
.01,-.011464,
.010571,-.011064,
.011064,-.010571,
.011464,-.01,
.011759,-.009368,
.011939,-.008695,
.012,-.008,
.012,.008,
.011939,.008695,
.011759,.009368,
.011464,.01,
.011064,.010571,
.010571,.011064,
.01,.011464,
.009368,.011759,
.008695,.011939,
.008,.012,
-.008,.012,
-.008695,.011939,
-.009368,.011759,
-.01,.011464,
-.010571,.011064,
-.011064,.010571,
-.011464,.01,
-.011759,.009368,
-.011939,.008695,
-.012,.008,
-.012,-.008,
-.011939,-.008695,
-.011759,-.009368,
-.011464,-.01,
-.011064,-.010571,
-.010571,-.011064,
-.01,-.011464,
-.009368,-.011759,
-.008695,-.011939,
-.008,-.012,
0.0*
%
%ADD29MACRO29*%
%AMMACRO15*
4,1,40,-.007,-.011,
.007,-.011,
.007695,-.010939,
.008368,-.010759,
.009,-.010464,
.009571,-.010064,
.010064,-.009571,
.010464,-.009,
.010759,-.008368,
.010939,-.007695,
.011,-.007,
.011,.007,
.010939,.007695,
.010759,.008368,
.010464,.009,
.010064,.009571,
.009571,.010064,
.009,.010464,
.008368,.010759,
.007695,.010939,
.007,.011,
-.007,.011,
-.007695,.010939,
-.008368,.010759,
-.009,.010464,
-.009571,.010064,
-.010064,.009571,
-.010464,.009,
-.010759,.008368,
-.010939,.007695,
-.011,.007,
-.011,-.007,
-.010939,-.007695,
-.010759,-.008368,
-.010464,-.009,
-.010064,-.009571,
-.009571,-.010064,
-.009,-.010464,
-.008368,-.010759,
-.007695,-.010939,
-.007,-.011,
0.0*
%
%ADD15MACRO15*%
%AMMACRO17*
4,1,40,-.011,.007,
-.011,-.007,
-.010939,-.007695,
-.010759,-.008368,
-.010464,-.009,
-.010064,-.009571,
-.009571,-.010064,
-.009,-.010464,
-.008368,-.010759,
-.007695,-.010939,
-.007,-.011,
.007,-.011,
.007695,-.010939,
.008368,-.010759,
.009,-.010464,
.009571,-.010064,
.010064,-.009571,
.010464,-.009,
.010759,-.008368,
.010939,-.007695,
.011,-.007,
.011,.007,
.010939,.007695,
.010759,.008368,
.010464,.009,
.010064,.009571,
.009571,.010064,
.009,.010464,
.008368,.010759,
.007695,.010939,
.007,.011,
-.007,.011,
-.007695,.010939,
-.008368,.010759,
-.009,.010464,
-.009571,.010064,
-.010064,.009571,
-.010464,.009,
-.010759,.008368,
-.010939,.007695,
-.011,.007,
0.0*
%
%ADD17MACRO17*%
%AMMACRO28*
4,1,40,-.008,-.012,
.008,-.012,
.008695,-.011939,
.009368,-.011759,
.01,-.011464,
.010571,-.011064,
.011064,-.010571,
.011464,-.01,
.011759,-.009368,
.011939,-.008695,
.012,-.008,
.012,.008,
.011939,.008695,
.011759,.009368,
.011464,.01,
.011064,.010571,
.010571,.011064,
.01,.011464,
.009368,.011759,
.008695,.011939,
.008,.012,
-.008,.012,
-.008695,.011939,
-.009368,.011759,
-.01,.011464,
-.010571,.011064,
-.011064,.010571,
-.011464,.01,
-.011759,.009368,
-.011939,.008695,
-.012,.008,
-.012,-.008,
-.011939,-.008695,
-.011759,-.009368,
-.011464,-.01,
-.011064,-.010571,
-.010571,-.011064,
-.01,-.011464,
-.009368,-.011759,
-.008695,-.011939,
-.008,-.012,
0.0*
%
%ADD28MACRO28*%
%AMMACRO16*
4,1,40,-.007,-.011,
.007,-.011,
.007695,-.010939,
.008368,-.010759,
.009,-.010464,
.009571,-.010064,
.010064,-.009571,
.010464,-.009,
.010759,-.008368,
.010939,-.007695,
.011,-.007,
.011,.007,
.010939,.007695,
.010759,.008368,
.010464,.009,
.010064,.009571,
.009571,.010064,
.009,.010464,
.008368,.010759,
.007695,.010939,
.007,.011,
-.007,.011,
-.007695,.010939,
-.008368,.010759,
-.009,.010464,
-.009571,.010064,
-.010064,.009571,
-.010464,.009,
-.010759,.008368,
-.010939,.007695,
-.011,.007,
-.011,-.007,
-.010939,-.007695,
-.010759,-.008368,
-.010464,-.009,
-.010064,-.009571,
-.009571,-.010064,
-.009,-.010464,
-.008368,-.010759,
-.007695,-.010939,
-.007,-.011,
0.0*
%
%ADD16MACRO16*%
%AMMACRO25*
4,1,40,-.011,.007,
-.011,-.007,
-.010939,-.007695,
-.010759,-.008368,
-.010464,-.009,
-.010064,-.009571,
-.009571,-.010064,
-.009,-.010464,
-.008368,-.010759,
-.007695,-.010939,
-.007,-.011,
.007,-.011,
.007695,-.010939,
.008368,-.010759,
.009,-.010464,
.009571,-.010064,
.010064,-.009571,
.010464,-.009,
.010759,-.008368,
.010939,-.007695,
.011,-.007,
.011,.007,
.010939,.007695,
.010759,.008368,
.010464,.009,
.010064,.009571,
.009571,.010064,
.009,.010464,
.008368,.010759,
.007695,.010939,
.007,.011,
-.007,.011,
-.007695,.010939,
-.008368,.010759,
-.009,.010464,
-.009571,.010064,
-.010064,.009571,
-.010464,.009,
-.010759,.008368,
-.010939,.007695,
-.011,.007,
0.0*
%
%ADD25MACRO25*%
%ADD32C,.02*%
%ADD33C,.006*%
G75*
%LPD*%
G75*
G54D10*
X25827Y-9492D03*
X141000Y43000D03*
X519227Y-9492D03*
G54D20*
X118110Y4456D03*
Y15230D03*
X103937Y4456D03*
Y15230D03*
X89764Y4456D03*
Y15230D03*
X75591Y4456D03*
Y15230D03*
X61417Y4456D03*
Y15230D03*
X47244Y4456D03*
Y15230D03*
G54D11*
X9000Y48000D03*
X164500Y48500D03*
G54D21*
X68750Y29500D03*
Y26940D03*
X75250D03*
X68750Y32060D03*
X75250D03*
G54D30*
X126000Y17200D03*
X133500Y29700D03*
G54D12*
X26811Y43012D03*
X56497Y50886D03*
G54D22*
X88940Y28250D03*
X94060D03*
X116060Y30250D03*
X113500D03*
X110940D03*
Y23750D03*
X116060D03*
X94060Y34750D03*
X91500D03*
X88940D03*
X128060Y30250D03*
X125500D03*
X122940D03*
Y23750D03*
X128060D03*
G54D13*
X26811Y50886D03*
X56497Y43012D03*
G54D31*
X126000Y13800D03*
X133500Y26300D03*
G54D32*
G01X-149983Y-76117D02*
Y-156117D01*
G01D02*
X864117D01*
G01X-153983Y-60117D02*
G02I-12000J0D01*
G01X-159133D02*
G02I-6850J0D01*
G01X-165983Y-76117D02*
Y-44117D01*
G01X-149983Y-60117D02*
X-181983D01*
G01X-149983Y-76117D02*
X864117D01*
G01X-149983Y-111617D02*
X864117D01*
G01X76617Y-76117D02*
Y-156117D01*
G01X214117Y-76117D02*
Y-156117D01*
G01X329117Y-76117D02*
Y-156117D01*
G01X496617Y-76117D02*
Y-156117D01*
G01X666617Y-76117D02*
Y-156117D01*
G01X864117Y-76117D02*
Y-156117D01*
G01X892117Y-60117D02*
G02I-12000J0D01*
G01X886967D02*
G02I-6850J0D01*
G01X880117Y-76117D02*
Y-44117D01*
G01X896117Y-60117D02*
X864117D01*
G54D14*
X30827Y43681D03*
X32796D03*
Y50217D03*
X30827D03*
X34764Y43681D03*
X36733D03*
X38701D03*
X40670D03*
X42638D03*
X44607D03*
X46575D03*
X48544D03*
X50512D03*
X52481D03*
Y50217D03*
X50512D03*
X48544D03*
X46575D03*
X44607D03*
X42638D03*
X40670D03*
X38701D03*
X36733D03*
X34764D03*
G54D23*
X62500Y29600D03*
X99000Y46500D03*
X78000Y42500D03*
G54D33*
G01X-137600Y-128617D02*
Y-146117D01*
X-128866D01*
G01X-113987Y-136784D02*
X-113113Y-135909D01*
X-112458Y-134451D01*
X-112021Y-132408D01*
X-112458Y-130659D01*
X-113331Y-129492D01*
X-114860Y-128617D01*
X-120755D01*
Y-146117D01*
X-113550D01*
X-112021Y-144951D01*
X-111148Y-143200D01*
X-110711Y-141159D01*
X-111148Y-139117D01*
X-112458Y-137367D01*
X-113987Y-136784D01*
X-120755D01*
G01X-93430Y-130076D02*
X-94740Y-129200D01*
X-96268Y-128617D01*
X-98015D01*
X-99980Y-129492D01*
X-101508Y-130950D01*
X-102600Y-132701D01*
X-103473Y-135617D01*
X-103692Y-138242D01*
X-103255Y-140867D01*
X-102600Y-142617D01*
X-101290Y-144367D01*
X-99761Y-145534D01*
X-98233Y-146117D01*
X-96705D01*
X-95176Y-145534D01*
X-93866Y-144659D01*
X-92774Y-143493D01*
G01X-67600Y-128617D02*
Y-146117D01*
X-58866D01*
G01X-41366D02*
X-50100D01*
Y-128617D01*
X-41366D01*
G01X-44860Y-137075D02*
X-50100D01*
G01X-33036Y-146117D02*
Y-128617D01*
X-28670D01*
X-26923Y-129492D01*
X-25613Y-130659D01*
X-24521Y-132408D01*
X-23648Y-134451D01*
X-23430Y-137367D01*
X-23648Y-140284D01*
X-24521Y-142326D01*
X-25613Y-144076D01*
X-26923Y-145242D01*
X-28670Y-146117D01*
X-33036D01*
G01X10260Y-135909D02*
X8732Y-134742D01*
X7422Y-134451D01*
X5675Y-135034D01*
X4365Y-136200D01*
X3492Y-138242D01*
X3273Y-140284D01*
X3492Y-142326D01*
X4365Y-144076D01*
X5675Y-145534D01*
X7422Y-146117D01*
X8950Y-145534D01*
X10260Y-144367D01*
G01X28197Y-146117D02*
Y-134451D01*
G01Y-136492D02*
X27324Y-135326D01*
X26013Y-134742D01*
X24485Y-134451D01*
X22957Y-135034D01*
X21647Y-136200D01*
X20773Y-137950D01*
X20337Y-140284D01*
X20773Y-142617D01*
X21647Y-144367D01*
X22957Y-145534D01*
X24485Y-146117D01*
X26013Y-145825D01*
X27324Y-144951D01*
X28197Y-143784D01*
G01X38710Y-146117D02*
Y-134451D01*
G01Y-136784D02*
X39802Y-135617D01*
X40894Y-134742D01*
X42422Y-134451D01*
X43513Y-134742D01*
X44824Y-135617D01*
G01X63197Y-128617D02*
Y-146117D01*
G01Y-143493D02*
X62324Y-144951D01*
X61013Y-145825D01*
X59485Y-146117D01*
X57739Y-145534D01*
X56429Y-144076D01*
X55555Y-142326D01*
X55337Y-140284D01*
X55555Y-138242D01*
X56429Y-136492D01*
X57739Y-135034D01*
X59485Y-134451D01*
X61013Y-134742D01*
X62105Y-135326D01*
X63197Y-136492D01*
G01X-77660Y-101117D02*
Y-83617D01*
X-71983Y-98200D01*
X-66306Y-83617D01*
Y-101117D01*
G01X-54483D02*
X-55793Y-100825D01*
X-57103Y-99659D01*
X-57977Y-97617D01*
X-58413Y-95284D01*
X-57977Y-92950D01*
X-57103Y-90909D01*
X-55793Y-89742D01*
X-54483Y-89451D01*
X-53173Y-89742D01*
X-51863Y-90909D01*
X-50990Y-92950D01*
X-50771Y-95284D01*
X-50990Y-97617D01*
X-51863Y-99659D01*
X-53173Y-100825D01*
X-54483Y-101117D01*
G01X-33053Y-83617D02*
Y-101117D01*
G01Y-98493D02*
X-33926Y-99951D01*
X-35237Y-100825D01*
X-36765Y-101117D01*
X-38511Y-100534D01*
X-39821Y-99076D01*
X-40695Y-97326D01*
X-40913Y-95284D01*
X-40695Y-93242D01*
X-39821Y-91492D01*
X-38511Y-90034D01*
X-36765Y-89451D01*
X-35237Y-89742D01*
X-34145Y-90326D01*
X-33053Y-91492D01*
G01X-22758Y-93242D02*
X-15771D01*
X-16426Y-91200D01*
X-17518Y-90034D01*
X-19046Y-89451D01*
X-20575Y-89742D01*
X-21885Y-90617D01*
X-22758Y-92659D01*
X-23195Y-94409D01*
Y-96159D01*
X-22758Y-97909D01*
X-21666Y-99659D01*
X-20356Y-100825D01*
X-18828Y-101117D01*
X-17300Y-100534D01*
X-15771Y-98784D01*
G01X-1983Y-101117D02*
Y-83617D01*
G01X110317Y-146117D02*
Y-128617D01*
X107697Y-132117D01*
G01Y-146117D02*
X112937D01*
G01X123669Y-138826D02*
X125197Y-136784D01*
X126507Y-135617D01*
X128254Y-135034D01*
X129782Y-135617D01*
X130874Y-136784D01*
X131747Y-138534D01*
X131965Y-140575D01*
X131747Y-142326D01*
X130874Y-144076D01*
X129563Y-145534D01*
X128035Y-146117D01*
X126289Y-145534D01*
X124760Y-143784D01*
X123887Y-141159D01*
X123669Y-138242D01*
X124105Y-134451D01*
X124760Y-132408D01*
X125852Y-130367D01*
X127380Y-128909D01*
X128909Y-128617D01*
X130437Y-129200D01*
X131529Y-130659D01*
G01X140514Y-142617D02*
X141823Y-144659D01*
X143570Y-145825D01*
X145535Y-146117D01*
X147282Y-145825D01*
X149029Y-144367D01*
X150120Y-142617D01*
X150339Y-140867D01*
X149902Y-138826D01*
X148374Y-137367D01*
X146845Y-136784D01*
X144880D01*
G01X146845D02*
X148155Y-135909D01*
X149247Y-134451D01*
X149684Y-132701D01*
X149247Y-130950D01*
X148155Y-129492D01*
X146190Y-128617D01*
X144225Y-128909D01*
X142260Y-130076D01*
G01X158669Y-138826D02*
X160197Y-136784D01*
X161507Y-135617D01*
X163254Y-135034D01*
X164782Y-135617D01*
X165874Y-136784D01*
X166747Y-138534D01*
X166965Y-140575D01*
X166747Y-142326D01*
X165874Y-144076D01*
X164563Y-145534D01*
X163035Y-146117D01*
X161289Y-145534D01*
X159760Y-143784D01*
X158887Y-141159D01*
X158669Y-138242D01*
X159105Y-134451D01*
X159760Y-132408D01*
X160852Y-130367D01*
X162380Y-128909D01*
X163909Y-128617D01*
X165437Y-129200D01*
X166529Y-130659D01*
G01X180317Y-146117D02*
X181845Y-145825D01*
X183592Y-144951D01*
X184684Y-143493D01*
X185120Y-141450D01*
X184684Y-139409D01*
X183374Y-137659D01*
X181409Y-136784D01*
X179225D01*
X177915Y-136200D01*
X176823Y-134742D01*
X176387Y-132701D01*
X177042Y-130659D01*
X178570Y-129200D01*
X180317Y-128617D01*
X182063Y-129200D01*
X183592Y-130659D01*
X184247Y-132701D01*
X183810Y-134742D01*
X182719Y-136200D01*
X181409Y-136784D01*
X179225D01*
X177260Y-137659D01*
X175950Y-139409D01*
X175514Y-141450D01*
X175950Y-143493D01*
X177042Y-144951D01*
X178789Y-145825D01*
X180317Y-146117D01*
G01X97200Y-101117D02*
Y-83617D01*
X102440D01*
X104187Y-84492D01*
X105497Y-86534D01*
X105934Y-88867D01*
X105497Y-91200D01*
X104405Y-92950D01*
X102440Y-93826D01*
X97200D01*
G01X123870Y-85076D02*
X122560Y-84200D01*
X121032Y-83617D01*
X119285D01*
X117320Y-84492D01*
X115792Y-85950D01*
X114700Y-87701D01*
X113827Y-90617D01*
X113608Y-93242D01*
X114045Y-95867D01*
X114700Y-97617D01*
X116010Y-99367D01*
X117539Y-100534D01*
X119067Y-101117D01*
X120595D01*
X122124Y-100534D01*
X123434Y-99659D01*
X124526Y-98493D01*
G01X138313Y-91784D02*
X139187Y-90909D01*
X139842Y-89451D01*
X140279Y-87408D01*
X139842Y-85659D01*
X138969Y-84492D01*
X137440Y-83617D01*
X131545D01*
Y-101117D01*
X138750D01*
X140279Y-99951D01*
X141152Y-98200D01*
X141589Y-96159D01*
X141152Y-94117D01*
X139842Y-92367D01*
X138313Y-91784D01*
X131545D01*
G01X147517Y-106950D02*
X160617D01*
G01X166545Y-101117D02*
Y-83617D01*
X176589Y-101117D01*
Y-83617D01*
G01X189067Y-101117D02*
X187320Y-100825D01*
X185792Y-99659D01*
X184482Y-97909D01*
X183608Y-95867D01*
X183172Y-93534D01*
Y-91200D01*
X183608Y-88867D01*
X184482Y-86825D01*
X185792Y-85076D01*
X187320Y-83909D01*
X189067Y-83617D01*
X190813Y-83909D01*
X192342Y-85076D01*
X193652Y-86825D01*
X194526Y-88867D01*
X194962Y-91200D01*
Y-93534D01*
X194526Y-95867D01*
X193652Y-97909D01*
X192342Y-99659D01*
X190813Y-100825D01*
X189067Y-101117D01*
G01X258282Y-143784D02*
X260029Y-145242D01*
X261994Y-146117D01*
X263740D01*
X265487Y-145242D01*
X266797Y-143784D01*
X267452Y-141742D01*
X267015Y-139701D01*
X265924Y-137950D01*
X263959Y-136784D01*
X261339Y-136200D01*
X259810Y-135034D01*
X259155Y-132992D01*
X259592Y-130950D01*
X260684Y-129492D01*
X262212Y-128617D01*
X263740D01*
X265269Y-129200D01*
X266579Y-130659D01*
G01X282113Y-136784D02*
X282987Y-135909D01*
X283642Y-134451D01*
X284079Y-132408D01*
X283642Y-130659D01*
X282769Y-129492D01*
X281240Y-128617D01*
X275345D01*
Y-146117D01*
X282550D01*
X284079Y-144951D01*
X284952Y-143200D01*
X285389Y-141159D01*
X284952Y-139117D01*
X283642Y-137367D01*
X282113Y-136784D01*
X275345D01*
G01X239908Y-83617D02*
X245367Y-101117D01*
X250826Y-83617D01*
G01X267234Y-101117D02*
X258500D01*
Y-83617D01*
X267234D01*
G01X263740Y-92075D02*
X258500D01*
G01X276000Y-101117D02*
Y-83617D01*
X281459D01*
X283205Y-84492D01*
X284297Y-85659D01*
X284734Y-87992D01*
X284297Y-90326D01*
X282987Y-91784D01*
X281459Y-92659D01*
X276000D01*
G01X281459D02*
X284734Y-101117D01*
G01X297867Y-101700D02*
X297430Y-101409D01*
Y-100825D01*
X297867Y-100534D01*
X298304Y-100825D01*
Y-101409D01*
X297867Y-101700D01*
G01X386567Y-128617D02*
Y-146117D01*
G01X381545Y-128617D02*
X391589D01*
G01X399482Y-143784D02*
X401229Y-145242D01*
X403194Y-146117D01*
X404940D01*
X406687Y-145242D01*
X407997Y-143784D01*
X408652Y-141742D01*
X408215Y-139701D01*
X407124Y-137950D01*
X405159Y-136784D01*
X402539Y-136200D01*
X401010Y-135034D01*
X400355Y-132992D01*
X400792Y-130950D01*
X401884Y-129492D01*
X403412Y-128617D01*
X404940D01*
X406469Y-129200D01*
X407779Y-130659D01*
G01X415890Y-146117D02*
Y-128617D01*
X421567Y-143200D01*
X427244Y-128617D01*
Y-146117D01*
G01X434264D02*
Y-128617D01*
X438630D01*
X440377Y-129492D01*
X441687Y-130659D01*
X442779Y-132408D01*
X443652Y-134451D01*
X443870Y-137367D01*
X443652Y-140284D01*
X442779Y-142326D01*
X441687Y-144076D01*
X440377Y-145242D01*
X438630Y-146117D01*
X434264D01*
G01X373450Y-83617D02*
Y-101117D01*
X382184D01*
G01X399247D02*
Y-89451D01*
G01Y-91492D02*
X398374Y-90326D01*
X397063Y-89742D01*
X395535Y-89451D01*
X394007Y-90034D01*
X392697Y-91200D01*
X391823Y-92950D01*
X391387Y-95284D01*
X391823Y-97617D01*
X392697Y-99367D01*
X394007Y-100534D01*
X395535Y-101117D01*
X397063Y-100825D01*
X398374Y-99951D01*
X399247Y-98784D01*
G01X408232Y-106367D02*
X409542Y-106950D01*
X411289Y-106367D01*
X412380Y-105201D01*
X413254Y-103742D01*
X414563Y-99076D01*
X417402Y-89451D01*
G01X410415D02*
X414563Y-99076D01*
G01X427042Y-93242D02*
X434029D01*
X433374Y-91200D01*
X432282Y-90034D01*
X430754Y-89451D01*
X429225Y-89742D01*
X427915Y-90617D01*
X427042Y-92659D01*
X426605Y-94409D01*
Y-96159D01*
X427042Y-97909D01*
X428134Y-99659D01*
X429444Y-100825D01*
X430972Y-101117D01*
X432500Y-100534D01*
X434029Y-98784D01*
G01X444760Y-101117D02*
Y-89451D01*
G01Y-91784D02*
X445852Y-90617D01*
X446944Y-89742D01*
X448472Y-89451D01*
X449563Y-89742D01*
X450874Y-90617D01*
G01X515564Y-101117D02*
Y-83617D01*
X519930D01*
X521677Y-84492D01*
X522987Y-85659D01*
X524079Y-87408D01*
X524952Y-89451D01*
X525170Y-92367D01*
X524952Y-95284D01*
X524079Y-97326D01*
X522987Y-99076D01*
X521677Y-100242D01*
X519930Y-101117D01*
X515564D01*
G01X534592Y-93242D02*
X541579D01*
X540924Y-91200D01*
X539832Y-90034D01*
X538304Y-89451D01*
X536775Y-89742D01*
X535465Y-90617D01*
X534592Y-92659D01*
X534155Y-94409D01*
Y-96159D01*
X534592Y-97909D01*
X535684Y-99659D01*
X536994Y-100825D01*
X538522Y-101117D01*
X540050Y-100534D01*
X541579Y-98784D01*
G01X552092Y-99076D02*
X553184Y-100242D01*
X554712Y-101117D01*
X556022D01*
X557332Y-100534D01*
X558205Y-99659D01*
X558642Y-98493D01*
X558424Y-96742D01*
X557550Y-95867D01*
X553620Y-94117D01*
X552747Y-92075D01*
X553184Y-90617D01*
X554057Y-89742D01*
X555367Y-89451D01*
X556677Y-89742D01*
X557987Y-90617D01*
G01X572867Y-89451D02*
Y-101117D01*
G01Y-84784D02*
X572430Y-84492D01*
Y-83909D01*
X572867Y-83617D01*
X573304Y-83909D01*
Y-84492D01*
X572867Y-84784D01*
G01X587310Y-105492D02*
X588839Y-106659D01*
X590585Y-106950D01*
X592113Y-106659D01*
X593424Y-105201D01*
X594297Y-103159D01*
Y-89451D01*
G01Y-91784D02*
X593424Y-90617D01*
X592113Y-89742D01*
X590585Y-89451D01*
X588839Y-90034D01*
X587747Y-91200D01*
X586873Y-93242D01*
X586437Y-95284D01*
X586655Y-97034D01*
X587529Y-99076D01*
X588839Y-100534D01*
X590585Y-101117D01*
X591895Y-100825D01*
X593424Y-99659D01*
X594297Y-98493D01*
G01X604155Y-101117D02*
Y-89451D01*
G01Y-92367D02*
X605029Y-90909D01*
X606339Y-89742D01*
X608085Y-89451D01*
X609613Y-89742D01*
X610924Y-90909D01*
X611579Y-92950D01*
Y-101117D01*
G01X622092Y-93242D02*
X629079D01*
X628424Y-91200D01*
X627332Y-90034D01*
X625804Y-89451D01*
X624275Y-89742D01*
X622965Y-90617D01*
X622092Y-92659D01*
X621655Y-94409D01*
Y-96159D01*
X622092Y-97909D01*
X623184Y-99659D01*
X624494Y-100825D01*
X626022Y-101117D01*
X627550Y-100534D01*
X629079Y-98784D01*
G01X639810Y-101117D02*
Y-89451D01*
G01Y-91784D02*
X640902Y-90617D01*
X641994Y-89742D01*
X643522Y-89451D01*
X644613Y-89742D01*
X645924Y-90617D01*
G01X559969Y-128617D02*
X568265D01*
X559969Y-146117D01*
X568265D01*
G01X581617D02*
X579870Y-145825D01*
X578342Y-144659D01*
X577032Y-142909D01*
X576158Y-140867D01*
X575722Y-138534D01*
Y-136200D01*
X576158Y-133867D01*
X577032Y-131825D01*
X578342Y-130076D01*
X579870Y-128909D01*
X581617Y-128617D01*
X583363Y-128909D01*
X584892Y-130076D01*
X586202Y-131825D01*
X587076Y-133867D01*
X587512Y-136200D01*
Y-138534D01*
X587076Y-140867D01*
X586202Y-142909D01*
X584892Y-144659D01*
X583363Y-145825D01*
X581617Y-146117D01*
G01X603484D02*
X594750D01*
Y-128617D01*
X603484D01*
G01X599990Y-137075D02*
X594750D01*
G01X686567Y-128617D02*
X684820Y-129200D01*
X683510Y-130659D01*
X682637Y-132408D01*
X681982Y-134742D01*
X681764Y-137367D01*
X681982Y-139992D01*
X682637Y-142326D01*
X683510Y-144076D01*
X684820Y-145534D01*
X686567Y-146117D01*
X688313Y-145534D01*
X689624Y-144076D01*
X690497Y-142326D01*
X691152Y-139992D01*
X691370Y-137367D01*
X691152Y-134742D01*
X690497Y-132408D01*
X689624Y-130659D01*
X688313Y-129200D01*
X686567Y-128617D01*
G01X699919Y-131534D02*
X701229Y-129784D01*
X702757Y-128909D01*
X704504Y-128617D01*
X706687Y-129200D01*
X708215Y-130659D01*
X708652Y-132408D01*
X708434Y-134159D01*
X707560Y-135617D01*
X703194Y-138534D01*
X701229Y-140575D01*
X699919Y-143493D01*
X699482Y-146117D01*
X708652D01*
G01X717637Y-146700D02*
X725497Y-128617D01*
G01X739067D02*
X737320Y-129200D01*
X736010Y-130659D01*
X735137Y-132408D01*
X734482Y-134742D01*
X734264Y-137367D01*
X734482Y-139992D01*
X735137Y-142326D01*
X736010Y-144076D01*
X737320Y-145534D01*
X739067Y-146117D01*
X740813Y-145534D01*
X742124Y-144076D01*
X742997Y-142326D01*
X743652Y-139992D01*
X743870Y-137367D01*
X743652Y-134742D01*
X742997Y-132408D01*
X742124Y-130659D01*
X740813Y-129200D01*
X739067Y-128617D01*
G01X756130Y-146117D02*
X756567Y-142326D01*
X757222Y-139117D01*
X758095Y-136200D01*
X759187Y-132992D01*
X760934Y-128617D01*
X752200D01*
G01X770137Y-146700D02*
X777997Y-128617D01*
G01X787419Y-131534D02*
X788729Y-129784D01*
X790257Y-128909D01*
X792004Y-128617D01*
X794187Y-129200D01*
X795715Y-130659D01*
X796152Y-132408D01*
X795934Y-134159D01*
X795060Y-135617D01*
X790694Y-138534D01*
X788729Y-140575D01*
X787419Y-143493D01*
X786982Y-146117D01*
X796152D01*
G01X809067Y-128617D02*
X807320Y-129200D01*
X806010Y-130659D01*
X805137Y-132408D01*
X804482Y-134742D01*
X804264Y-137367D01*
X804482Y-139992D01*
X805137Y-142326D01*
X806010Y-144076D01*
X807320Y-145534D01*
X809067Y-146117D01*
X810813Y-145534D01*
X812124Y-144076D01*
X812997Y-142326D01*
X813652Y-139992D01*
X813870Y-137367D01*
X813652Y-134742D01*
X812997Y-132408D01*
X812124Y-130659D01*
X810813Y-129200D01*
X809067Y-128617D01*
G01X826567Y-146117D02*
Y-128617D01*
X823947Y-132117D01*
G01Y-146117D02*
X829187D01*
G01X843630D02*
X844067Y-142326D01*
X844722Y-139117D01*
X845595Y-136200D01*
X846687Y-132992D01*
X848434Y-128617D01*
X839700D01*
G01X734264Y-101117D02*
Y-83617D01*
X738630D01*
X740377Y-84492D01*
X741687Y-85659D01*
X742779Y-87408D01*
X743652Y-89451D01*
X743870Y-92367D01*
X743652Y-95284D01*
X742779Y-97326D01*
X741687Y-99076D01*
X740377Y-100242D01*
X738630Y-101117D01*
X734264D01*
G01X760497D02*
Y-89451D01*
G01Y-91492D02*
X759624Y-90326D01*
X758313Y-89742D01*
X756785Y-89451D01*
X755257Y-90034D01*
X753947Y-91200D01*
X753073Y-92950D01*
X752637Y-95284D01*
X753073Y-97617D01*
X753947Y-99367D01*
X755257Y-100534D01*
X756785Y-101117D01*
X758313Y-100825D01*
X759624Y-99951D01*
X760497Y-98784D01*
G01X774067Y-83617D02*
Y-101117D01*
G01X771010Y-89451D02*
X777124D01*
G01X788292Y-93242D02*
X795279D01*
X794624Y-91200D01*
X793532Y-90034D01*
X792004Y-89451D01*
X790475Y-89742D01*
X789165Y-90617D01*
X788292Y-92659D01*
X787855Y-94409D01*
Y-96159D01*
X788292Y-97909D01*
X789384Y-99659D01*
X790694Y-100825D01*
X792222Y-101117D01*
X793750Y-100534D01*
X795279Y-98784D01*
G01X0Y-11811D02*
G03X7874Y-19685I7874J0D01*
G01X37008Y0D02*
G03Y-7874I0J-3937D01*
G01X11811D02*
G03Y0I0J3937D01*
G01X0Y-7874D02*
Y-11811D01*
G01X7874Y-19685D02*
X181690D01*
G01X0Y-7874D02*
X11811D01*
G01X25985Y19685D02*
G03X9449I-8268J0D01*
G01D02*
G03X25985I8268J0D01*
G01D02*
G03X9449I-8268J0D01*
G01D02*
G03X25985I8268J0D01*
G01D02*
G03X9449I-8268J0D01*
G01D02*
G03X25985I8268J0D01*
G01D02*
G03X9449I-8268J0D01*
G01D02*
G03X25985I8268J0D01*
G01X9449D02*
G03X25985I8268J0D01*
G01D02*
G03X9449I-8268J0D01*
G01D02*
G03X25985I8268J0D01*
G01D02*
G03X9449I-8268J0D01*
G01X3937Y0D02*
X173229D01*
G01X0Y3937D02*
G03X3937Y0I3937J0D01*
G01X0Y57874D02*
Y3937D01*
G01X37008Y69685D02*
G03Y61811I0J-3937D01*
G01X11811D02*
G03Y69685I0J3937D01*
G01X25985Y89370D02*
G03X9449I-8268J0D01*
G01D02*
G03X25985I8268J0D01*
G01D02*
G03X9449I-8268J0D01*
G01D02*
G03X25985I8268J0D01*
G01D02*
G03X9449I-8268J0D01*
G01D02*
G03X25985I8268J0D01*
G01D02*
G03X9449I-8268J0D01*
G01D02*
G03X25985I8268J0D01*
G01X9449D02*
G03X25985I8268J0D01*
G01D02*
G03X9449I-8268J0D01*
G01D02*
G03X25985I8268J0D01*
G01D02*
G03X9449I-8268J0D01*
G01X3937Y69685D02*
X173229D01*
G01X0Y73622D02*
G03X3937Y69685I3937J0D01*
G01X0Y127559D02*
Y73622D01*
G01X3937Y61811D02*
G03X0Y57874I0J-3937D01*
G01X173229Y61811D02*
X3937D01*
G01X37008Y139370D02*
G03Y131496I0J-3937D01*
G01X11811D02*
G03Y139370I0J3937D01*
G01X25985Y159055D02*
G03X9449I-8268J0D01*
G01D02*
G03X25985I8268J0D01*
G01D02*
G03X9449I-8268J0D01*
G01D02*
G03X25985I8268J0D01*
G01D02*
G03X9449I-8268J0D01*
G01D02*
G03X25985I8268J0D01*
G01D02*
G03X9449I-8268J0D01*
G01D02*
G03X25985I8268J0D01*
G01X9449D02*
G03X25985I8268J0D01*
G01D02*
G03X9449I-8268J0D01*
G01D02*
G03X25985I8268J0D01*
G01D02*
G03X9449I-8268J0D01*
G01X3937Y139370D02*
X173229D01*
G01X0Y143307D02*
G03X3937Y139370I3937J0D01*
G01X0Y197244D02*
Y143307D01*
G01X3937Y131496D02*
G03X0Y127559I0J-3937D01*
G01X173229Y131496D02*
X3937D01*
G01X37008Y278740D02*
G03Y270866I0J-3937D01*
G01X11811D02*
G03Y278740I0J3937D01*
G01X37008Y209055D02*
G03Y201181I0J-3937D01*
G01X11811D02*
G03Y209055I0J3937D01*
G01X3937Y278740D02*
X173229D01*
G01X0Y282677D02*
G03X3937Y278740I3937J0D01*
G01X25985Y228740D02*
G03X9449I-8268J0D01*
G01D02*
G03X25985I8268J0D01*
G01D02*
G03X9449I-8268J0D01*
G01D02*
G03X25985I8268J0D01*
G01D02*
G03X9449I-8268J0D01*
G01D02*
G03X25985I8268J0D01*
G01D02*
G03X9449I-8268J0D01*
G01D02*
G03X25985I8268J0D01*
G01X9449D02*
G03X25985I8268J0D01*
G01D02*
G03X9449I-8268J0D01*
G01D02*
G03X25985I8268J0D01*
G01D02*
G03X9449I-8268J0D01*
G01X3937Y209055D02*
X173229D01*
G01X0Y212992D02*
G03X3937Y209055I3937J0D01*
G01X0Y266929D02*
Y212992D01*
G01X3937Y270866D02*
G03X0Y266929I0J-3937D01*
G01X173229Y270866D02*
X3937D01*
G01Y201181D02*
G03X0Y197244I0J-3937D01*
G01X173229Y201181D02*
X3937D01*
G01X37008Y348425D02*
G03Y340551I0J-3937D01*
G01X11811D02*
G03Y348425I0J3937D01*
G01X9449Y368110D02*
G03X25985I8268J0D01*
G01X9449D02*
G03X25985I8268J0D01*
G01X9449D02*
G03X25985I8268J0D01*
G01X9449D02*
G03X25985I8268J0D01*
G01X9449D02*
G03X25985I8268J0D01*
G01X9449D02*
G03X25985I8268J0D01*
G01X3937Y348425D02*
X173229D01*
G01X0Y352362D02*
G03X3937Y348425I3937J0D01*
G01X0Y406299D02*
Y352362D01*
G01X25985Y298425D02*
G03X9449I-8268J0D01*
G01D02*
G03X25985I8268J0D01*
G01D02*
G03X9449I-8268J0D01*
G01D02*
G03X25985I8268J0D01*
G01D02*
G03X9449I-8268J0D01*
G01D02*
G03X25985I8268J0D01*
G01D02*
G03X9449I-8268J0D01*
G01D02*
G03X25985I8268J0D01*
G01X9449D02*
G03X25985I8268J0D01*
G01D02*
G03X9449I-8268J0D01*
G01D02*
G03X25985I8268J0D01*
G01D02*
G03X9449I-8268J0D01*
G01X0Y336614D02*
Y282677D01*
G01X3937Y340551D02*
G03X0Y336614I0J-3937D01*
G01X173229Y340551D02*
X3937D01*
G01X37008Y418110D02*
G03Y410236I0J-3937D01*
G01X11811D02*
G03Y418110I0J3937D01*
G01X25985Y437795D02*
G03X9449I-8268J0D01*
G01D02*
G03X25985I8268J0D01*
G01D02*
G03X9449I-8268J0D01*
G01D02*
G03X25985I8268J0D01*
G01D02*
G03X9449I-8268J0D01*
G01D02*
G03X25985I8268J0D01*
G01D02*
G03X9449I-8268J0D01*
G01D02*
G03X25985I8268J0D01*
G01X9449D02*
G03X25985I8268J0D01*
G01D02*
G03X9449I-8268J0D01*
G01D02*
G03X25985I8268J0D01*
G01D02*
G03X9449I-8268J0D01*
G01X3937Y418110D02*
X173229D01*
G01X0Y422047D02*
G03X3937Y418110I3937J0D01*
G01X0Y475984D02*
Y422047D01*
G01X25985Y368110D02*
G03X9449I-8268J0D01*
G01X25985D02*
G03X9449I-8268J0D01*
G01X25985D02*
G03X9449I-8268J0D01*
G01X25985D02*
G03X9449I-8268J0D01*
G01X25985D02*
G03X9449I-8268J0D01*
G01X25985D02*
G03X9449I-8268J0D01*
G01X3937Y410236D02*
G03X0Y406299I0J-3937D01*
G01X173229Y410236D02*
X3937D01*
G01X37008Y487795D02*
G03Y479921I0J-3937D01*
G01X11811D02*
G03Y487795I0J3937D01*
G01X25985Y507480D02*
G03X9449I-8268J0D01*
G01D02*
G03X25985I8268J0D01*
G01D02*
G03X9449I-8268J0D01*
G01D02*
G03X25985I8268J0D01*
G01D02*
G03X9449I-8268J0D01*
G01D02*
G03X25985I8268J0D01*
G01D02*
G03X9449I-8268J0D01*
G01D02*
G03X25985I8268J0D01*
G01X9449D02*
G03X25985I8268J0D01*
G01D02*
G03X9449I-8268J0D01*
G01D02*
G03X25985I8268J0D01*
G01D02*
G03X9449I-8268J0D01*
G01X3937Y487795D02*
X173229D01*
G01X0Y491732D02*
G03X3937Y487795I3937J0D01*
G01X0Y545669D02*
Y491732D01*
G01X3937Y479921D02*
G03X0Y475984I0J-3937D01*
G01X173229Y479921D02*
X3937D01*
G01X37008Y557480D02*
G03Y549606I0J-3937D01*
G01X11811D02*
G03Y557480I0J3937D01*
G01X25985Y577165D02*
G03X9449I-8268J0D01*
G01D02*
G03X25985I8268J0D01*
G01D02*
G03X9449I-8268J0D01*
G01D02*
G03X25985I8268J0D01*
G01D02*
G03X9449I-8268J0D01*
G01D02*
G03X25985I8268J0D01*
G01D02*
G03X9449I-8268J0D01*
G01D02*
G03X25985I8268J0D01*
G01X9449D02*
G03X25985I8268J0D01*
G01D02*
G03X9449I-8268J0D01*
G01D02*
G03X25985I8268J0D01*
G01D02*
G03X9449I-8268J0D01*
G01X3937Y557480D02*
X173229D01*
G01X0Y561417D02*
G03X3937Y557480I3937J0D01*
G01X0Y615354D02*
Y561417D01*
G01X3937Y549606D02*
G03X0Y545669I0J-3937D01*
G01X173229Y549606D02*
X3937D01*
G01X37008Y627165D02*
G03Y619291I0J-3937D01*
G01X11811D02*
G03Y627165I0J3937D01*
G01X25985Y646850D02*
G03X9449I-8268J0D01*
G01D02*
G03X25985I8268J0D01*
G01D02*
G03X9449I-8268J0D01*
G01D02*
G03X25985I8268J0D01*
G01D02*
G03X9449I-8268J0D01*
G01D02*
G03X25985I8268J0D01*
G01D02*
G03X9449I-8268J0D01*
G01D02*
G03X25985I8268J0D01*
G01X9449D02*
G03X25985I8268J0D01*
G01D02*
G03X9449I-8268J0D01*
G01D02*
G03X25985I8268J0D01*
G01D02*
G03X9449I-8268J0D01*
G01X3937Y627165D02*
X173229D01*
G01X0Y631102D02*
G03X3937Y627165I3937J0D01*
G01X0Y685039D02*
Y631102D01*
G01X3937Y688976D02*
G03X0Y685039I0J-3937D01*
G01X173229Y688976D02*
X3937D01*
G01Y619291D02*
G03X0Y615354I0J-3937D01*
G01X173229Y619291D02*
X3937D01*
G01X37008Y-7874D02*
X140158D01*
G01X196851D02*
G03Y0I0J3937D01*
G01X189564Y-19685D02*
G03X181690I-3937J0D01*
G01X165355Y0D02*
G03Y-7874I0J-3937D01*
G01X140158D02*
G03Y0I0J3937D01*
G01X185040Y18307D02*
G03X177166I-3937J0D01*
G01X189564Y-19685D02*
X539370D01*
G01X165355Y-7874D02*
X196851D01*
G01X211024Y19685D02*
G03X194489I-8267J0D01*
G01D02*
G03X211024I8267J0D01*
G01D02*
G03X194489I-8267J0D01*
G01D02*
G03X211024I8267J0D01*
G01D02*
G03X194489I-8267J0D01*
G01D02*
G03X211024I8267J0D01*
G01D02*
G03X194489I-8267J0D01*
G01D02*
G03X211024I8267J0D01*
G01X194489D02*
G03X211024I8267J0D01*
G01D02*
G03X194489I-8267J0D01*
G01D02*
G03X211024I8267J0D01*
G01D02*
G03X194489I-8267J0D01*
G01X188977Y0D02*
X358268D01*
G01X185040Y3937D02*
G03X188977Y0I3937J0D01*
G01X185040Y57874D02*
Y3937D01*
G01X167717Y19685D02*
G03X151181I-8268J0D01*
G01D02*
G03X167717I8268J0D01*
G01D02*
G03X151181I-8268J0D01*
G01D02*
G03X167717I8268J0D01*
G01D02*
G03X151181I-8268J0D01*
G01D02*
G03X167717I8268J0D01*
G01D02*
G03X151181I-8268J0D01*
G01D02*
G03X167717I8268J0D01*
G01X151181D02*
G03X167717I8268J0D01*
G01D02*
G03X151181I-8268J0D01*
G01D02*
G03X167717I8268J0D01*
G01D02*
G03X151181I-8268J0D01*
G01X177166Y3937D02*
Y57874D01*
G01X173229Y0D02*
G03X177166Y3937I0J3937D01*
G01X185040Y87992D02*
G03X177166I-3937J0D01*
G01Y113189D02*
G03X185040I3937J0D01*
G01X196851Y61811D02*
G03Y69685I0J3937D01*
G01X165355D02*
G03Y61811I0J-3937D01*
G01X140158D02*
G03Y69685I0J3937D01*
G01X177166Y43504D02*
G03X185040I3937J0D01*
G01X167717Y89370D02*
G03X151181I-8268J0D01*
G01D02*
G03X167717I8268J0D01*
G01D02*
G03X151181I-8268J0D01*
G01D02*
G03X167717I8268J0D01*
G01D02*
G03X151181I-8268J0D01*
G01D02*
G03X167717I8268J0D01*
G01D02*
G03X151181I-8268J0D01*
G01D02*
G03X167717I8268J0D01*
G01X151181D02*
G03X167717I8268J0D01*
G01D02*
G03X151181I-8268J0D01*
G01D02*
G03X167717I8268J0D01*
G01D02*
G03X151181I-8268J0D01*
G01X177166Y73622D02*
Y127559D01*
G01X173229Y69685D02*
G03X177166Y73622I0J3937D01*
G01X211024Y89370D02*
G03X194489I-8267J0D01*
G01D02*
G03X211024I8267J0D01*
G01D02*
G03X194489I-8267J0D01*
G01D02*
G03X211024I8267J0D01*
G01D02*
G03X194489I-8267J0D01*
G01D02*
G03X211024I8267J0D01*
G01D02*
G03X194489I-8267J0D01*
G01D02*
G03X211024I8267J0D01*
G01X194489D02*
G03X211024I8267J0D01*
G01D02*
G03X194489I-8267J0D01*
G01D02*
G03X211024I8267J0D01*
G01D02*
G03X194489I-8267J0D01*
G01X188977Y69685D02*
X358268D01*
G01X185040Y73622D02*
G03X188977Y69685I3937J0D01*
G01X185040Y127559D02*
Y73622D01*
G01X188977Y61811D02*
G03X185040Y57874I0J-3937D01*
G01X358268Y61811D02*
X188977D01*
G01X177166Y57874D02*
G03X173229Y61811I-3937J0D01*
G01X185040Y157677D02*
G03X177166I-3937J0D01*
G01Y182874D02*
G03X185040I3937J0D01*
G01X196851Y131496D02*
G03Y139370I0J3937D01*
G01X165355D02*
G03Y131496I0J-3937D01*
G01X140158D02*
G03Y139370I0J3937D01*
G01X167717Y159055D02*
G03X151181I-8268J0D01*
G01D02*
G03X167717I8268J0D01*
G01D02*
G03X151181I-8268J0D01*
G01D02*
G03X167717I8268J0D01*
G01D02*
G03X151181I-8268J0D01*
G01D02*
G03X167717I8268J0D01*
G01D02*
G03X151181I-8268J0D01*
G01D02*
G03X167717I8268J0D01*
G01X151181D02*
G03X167717I8268J0D01*
G01D02*
G03X151181I-8268J0D01*
G01D02*
G03X167717I8268J0D01*
G01D02*
G03X151181I-8268J0D01*
G01X177166Y143307D02*
Y197244D01*
G01X173229Y139370D02*
G03X177166Y143307I0J3937D01*
G01Y127559D02*
G03X173229Y131496I-3937J0D01*
G01X211024Y159055D02*
G03X194489I-8267J0D01*
G01D02*
G03X211024I8267J0D01*
G01D02*
G03X194489I-8267J0D01*
G01D02*
G03X211024I8267J0D01*
G01D02*
G03X194489I-8267J0D01*
G01D02*
G03X211024I8267J0D01*
G01D02*
G03X194489I-8267J0D01*
G01D02*
G03X211024I8267J0D01*
G01X194489D02*
G03X211024I8267J0D01*
G01D02*
G03X194489I-8267J0D01*
G01D02*
G03X211024I8267J0D01*
G01D02*
G03X194489I-8267J0D01*
G01X188977Y139370D02*
X358268D01*
G01X185040Y143307D02*
G03X188977Y139370I3937J0D01*
G01X185040Y197244D02*
Y143307D01*
G01X188977Y131496D02*
G03X185040Y127559I0J-3937D01*
G01X358268Y131496D02*
X188977D01*
G01X185040Y227362D02*
G03X177166I-3937J0D01*
G01Y252559D02*
G03X185040I3937J0D01*
G01X196851Y270866D02*
G03Y278740I0J3937D01*
G01X165355D02*
G03Y270866I0J-3937D01*
G01X140158D02*
G03Y278740I0J3937D01*
G01X196851Y201181D02*
G03Y209055I0J3937D01*
G01X165355D02*
G03Y201181I0J-3937D01*
G01X140158D02*
G03Y209055I0J3937D01*
G01X173229Y278740D02*
G03X177166Y282677I0J3937D01*
G01X188977Y278740D02*
X358268D01*
G01X185040Y282677D02*
G03X188977Y278740I3937J0D01*
G01X167717Y228740D02*
G03X151181I-8268J0D01*
G01D02*
G03X167717I8268J0D01*
G01D02*
G03X151181I-8268J0D01*
G01D02*
G03X167717I8268J0D01*
G01D02*
G03X151181I-8268J0D01*
G01D02*
G03X167717I8268J0D01*
G01D02*
G03X151181I-8268J0D01*
G01D02*
G03X167717I8268J0D01*
G01X151181D02*
G03X167717I8268J0D01*
G01D02*
G03X151181I-8268J0D01*
G01D02*
G03X167717I8268J0D01*
G01D02*
G03X151181I-8268J0D01*
G01X177166Y212992D02*
Y266929D01*
G01X173229Y209055D02*
G03X177166Y212992I0J3937D01*
G01Y266929D02*
G03X173229Y270866I-3937J0D01*
G01X211024Y228740D02*
G03X194489I-8267J0D01*
G01D02*
G03X211024I8267J0D01*
G01D02*
G03X194489I-8267J0D01*
G01D02*
G03X211024I8267J0D01*
G01D02*
G03X194489I-8267J0D01*
G01D02*
G03X211024I8267J0D01*
G01D02*
G03X194489I-8267J0D01*
G01D02*
G03X211024I8267J0D01*
G01X194489D02*
G03X211024I8267J0D01*
G01D02*
G03X194489I-8267J0D01*
G01D02*
G03X211024I8267J0D01*
G01D02*
G03X194489I-8267J0D01*
G01X188977Y209055D02*
X358268D01*
G01X185040Y212992D02*
G03X188977Y209055I3937J0D01*
G01X185040Y266929D02*
Y212992D01*
G01X188977Y270866D02*
G03X185040Y266929I0J-3937D01*
G01X358268Y270866D02*
X188977D01*
G01X177166Y197244D02*
G03X173229Y201181I-3937J0D01*
G01X188977D02*
G03X185040Y197244I0J-3937D01*
G01X358268Y201181D02*
X188977D01*
G01X185040Y297047D02*
G03X177166I-3937J0D01*
G01Y322244D02*
G03X185040I3937J0D01*
G01X196851Y340551D02*
G03Y348425I0J3937D01*
G01X165355D02*
G03Y340551I0J-3937D01*
G01X140158D02*
G03Y348425I0J3937D01*
G01X151181Y368110D02*
G03X167717I8268J0D01*
G01X151181D02*
G03X167717I8268J0D01*
G01X151181D02*
G03X167717I8268J0D01*
G01X151181D02*
G03X167717I8268J0D01*
G01X151181D02*
G03X167717I8268J0D01*
G01X151181D02*
G03X167717I8268J0D01*
G01X177166Y352362D02*
Y406299D01*
G01X173229Y348425D02*
G03X177166Y352362I0J3937D01*
G01X194489Y368110D02*
G03X211024I8267J0D01*
G01X194489D02*
G03X211024I8267J0D01*
G01X194489D02*
G03X211024I8267J0D01*
G01X194489D02*
G03X211024I8267J0D01*
G01X194489D02*
G03X211024I8267J0D01*
G01X194489D02*
G03X211024I8267J0D01*
G01X188977Y348425D02*
X358268D01*
G01X185040Y352362D02*
G03X188977Y348425I3937J0D01*
G01X185040Y406299D02*
Y352362D01*
G01X167717Y298425D02*
G03X151181I-8268J0D01*
G01D02*
G03X167717I8268J0D01*
G01D02*
G03X151181I-8268J0D01*
G01D02*
G03X167717I8268J0D01*
G01D02*
G03X151181I-8268J0D01*
G01D02*
G03X167717I8268J0D01*
G01D02*
G03X151181I-8268J0D01*
G01D02*
G03X167717I8268J0D01*
G01X151181D02*
G03X167717I8268J0D01*
G01D02*
G03X151181I-8268J0D01*
G01D02*
G03X167717I8268J0D01*
G01D02*
G03X151181I-8268J0D01*
G01X177166Y282677D02*
Y336614D01*
G01D02*
G03X173229Y340551I-3937J0D01*
G01X211024Y298425D02*
G03X194489I-8267J0D01*
G01D02*
G03X211024I8267J0D01*
G01D02*
G03X194489I-8267J0D01*
G01D02*
G03X211024I8267J0D01*
G01D02*
G03X194489I-8267J0D01*
G01D02*
G03X211024I8267J0D01*
G01D02*
G03X194489I-8267J0D01*
G01D02*
G03X211024I8267J0D01*
G01X194489D02*
G03X211024I8267J0D01*
G01D02*
G03X194489I-8267J0D01*
G01D02*
G03X211024I8267J0D01*
G01D02*
G03X194489I-8267J0D01*
G01X185040Y336614D02*
Y282677D01*
G01X188977Y340551D02*
G03X185040Y336614I0J-3937D01*
G01X358268Y340551D02*
X188977D01*
G01X185040Y436417D02*
G03X177166I-3937J0D01*
G01X185040Y366732D02*
G03X177166I-3937J0D01*
G01Y391929D02*
G03X185040I3937J0D01*
G01X196851Y410236D02*
G03Y418110I0J3937D01*
G01X165355D02*
G03Y410236I0J-3937D01*
G01X140158D02*
G03Y418110I0J3937D01*
G01X167717Y437795D02*
G03X151181I-8268J0D01*
G01D02*
G03X167717I8268J0D01*
G01D02*
G03X151181I-8268J0D01*
G01D02*
G03X167717I8268J0D01*
G01D02*
G03X151181I-8268J0D01*
G01D02*
G03X167717I8268J0D01*
G01D02*
G03X151181I-8268J0D01*
G01D02*
G03X167717I8268J0D01*
G01X151181D02*
G03X167717I8268J0D01*
G01D02*
G03X151181I-8268J0D01*
G01D02*
G03X167717I8268J0D01*
G01D02*
G03X151181I-8268J0D01*
G01X177166Y422047D02*
Y475984D01*
G01X173229Y418110D02*
G03X177166Y422047I0J3937D01*
G01X211024Y437795D02*
G03X194489I-8267J0D01*
G01D02*
G03X211024I8267J0D01*
G01D02*
G03X194489I-8267J0D01*
G01D02*
G03X211024I8267J0D01*
G01D02*
G03X194489I-8267J0D01*
G01D02*
G03X211024I8267J0D01*
G01D02*
G03X194489I-8267J0D01*
G01D02*
G03X211024I8267J0D01*
G01X194489D02*
G03X211024I8267J0D01*
G01D02*
G03X194489I-8267J0D01*
G01D02*
G03X211024I8267J0D01*
G01D02*
G03X194489I-8267J0D01*
G01X188977Y418110D02*
X358268D01*
G01X185040Y422047D02*
G03X188977Y418110I3937J0D01*
G01X185040Y475984D02*
Y422047D01*
G01X167717Y368110D02*
G03X151181I-8268J0D01*
G01X167717D02*
G03X151181I-8268J0D01*
G01X167717D02*
G03X151181I-8268J0D01*
G01X167717D02*
G03X151181I-8268J0D01*
G01X167717D02*
G03X151181I-8268J0D01*
G01X167717D02*
G03X151181I-8268J0D01*
G01X177166Y406299D02*
G03X173229Y410236I-3937J0D01*
G01X211024Y368110D02*
G03X194489I-8267J0D01*
G01X211024D02*
G03X194489I-8267J0D01*
G01X211024D02*
G03X194489I-8267J0D01*
G01X211024D02*
G03X194489I-8267J0D01*
G01X211024D02*
G03X194489I-8267J0D01*
G01X211024D02*
G03X194489I-8267J0D01*
G01X188977Y410236D02*
G03X185040Y406299I0J-3937D01*
G01X358268Y410236D02*
X188977D01*
G01X185040Y506102D02*
G03X177166I-3937J0D01*
G01Y531299D02*
G03X185040I3937J0D01*
G01X177166Y461614D02*
G03X185040I3937J0D01*
G01X196851Y479921D02*
G03Y487795I0J3937D01*
G01X165355D02*
G03Y479921I0J-3937D01*
G01X140158D02*
G03Y487795I0J3937D01*
G01X167717Y507480D02*
G03X151181I-8268J0D01*
G01D02*
G03X167717I8268J0D01*
G01D02*
G03X151181I-8268J0D01*
G01D02*
G03X167717I8268J0D01*
G01D02*
G03X151181I-8268J0D01*
G01D02*
G03X167717I8268J0D01*
G01D02*
G03X151181I-8268J0D01*
G01D02*
G03X167717I8268J0D01*
G01X151181D02*
G03X167717I8268J0D01*
G01D02*
G03X151181I-8268J0D01*
G01D02*
G03X167717I8268J0D01*
G01D02*
G03X151181I-8268J0D01*
G01X177166Y491732D02*
Y545669D01*
G01X173229Y487795D02*
G03X177166Y491732I0J3937D01*
G01X211024Y507480D02*
G03X194489I-8267J0D01*
G01D02*
G03X211024I8267J0D01*
G01D02*
G03X194489I-8267J0D01*
G01D02*
G03X211024I8267J0D01*
G01D02*
G03X194489I-8267J0D01*
G01D02*
G03X211024I8267J0D01*
G01D02*
G03X194489I-8267J0D01*
G01D02*
G03X211024I8267J0D01*
G01X194489D02*
G03X211024I8267J0D01*
G01D02*
G03X194489I-8267J0D01*
G01D02*
G03X211024I8267J0D01*
G01D02*
G03X194489I-8267J0D01*
G01X188977Y487795D02*
X358268D01*
G01X185040Y491732D02*
G03X188977Y487795I3937J0D01*
G01X185040Y545669D02*
Y491732D01*
G01X177166Y475984D02*
G03X173229Y479921I-3937J0D01*
G01X188977D02*
G03X185040Y475984I0J-3937D01*
G01X358268Y479921D02*
X188977D01*
G01X185040Y575787D02*
G03X177166I-3937J0D01*
G01Y600984D02*
G03X185040I3937J0D01*
G01X196851Y549606D02*
G03Y557480I0J3937D01*
G01X165355D02*
G03Y549606I0J-3937D01*
G01X140158D02*
G03Y557480I0J3937D01*
G01X167717Y577165D02*
G03X151181I-8268J0D01*
G01D02*
G03X167717I8268J0D01*
G01D02*
G03X151181I-8268J0D01*
G01D02*
G03X167717I8268J0D01*
G01D02*
G03X151181I-8268J0D01*
G01D02*
G03X167717I8268J0D01*
G01D02*
G03X151181I-8268J0D01*
G01D02*
G03X167717I8268J0D01*
G01X151181D02*
G03X167717I8268J0D01*
G01D02*
G03X151181I-8268J0D01*
G01D02*
G03X167717I8268J0D01*
G01D02*
G03X151181I-8268J0D01*
G01X177166Y561417D02*
Y615354D01*
G01X173229Y557480D02*
G03X177166Y561417I0J3937D01*
G01X211024Y577165D02*
G03X194489I-8267J0D01*
G01D02*
G03X211024I8267J0D01*
G01D02*
G03X194489I-8267J0D01*
G01D02*
G03X211024I8267J0D01*
G01D02*
G03X194489I-8267J0D01*
G01D02*
G03X211024I8267J0D01*
G01D02*
G03X194489I-8267J0D01*
G01D02*
G03X211024I8267J0D01*
G01X194489D02*
G03X211024I8267J0D01*
G01D02*
G03X194489I-8267J0D01*
G01D02*
G03X211024I8267J0D01*
G01D02*
G03X194489I-8267J0D01*
G01X188977Y557480D02*
X358268D01*
G01X185040Y561417D02*
G03X188977Y557480I3937J0D01*
G01X185040Y615354D02*
Y561417D01*
G01X177166Y545669D02*
G03X173229Y549606I-3937J0D01*
G01X188977D02*
G03X185040Y545669I0J-3937D01*
G01X358268Y549606D02*
X188977D01*
G01X185040Y645472D02*
G03X177166I-3937J0D01*
G01Y670669D02*
G03X185040I3937J0D01*
G01X196851Y619291D02*
G03Y627165I0J3937D01*
G01X165355D02*
G03Y619291I0J-3937D01*
G01X140158D02*
G03Y627165I0J3937D01*
G01X167717Y646850D02*
G03X151181I-8268J0D01*
G01D02*
G03X167717I8268J0D01*
G01D02*
G03X151181I-8268J0D01*
G01D02*
G03X167717I8268J0D01*
G01D02*
G03X151181I-8268J0D01*
G01D02*
G03X167717I8268J0D01*
G01D02*
G03X151181I-8268J0D01*
G01D02*
G03X167717I8268J0D01*
G01X151181D02*
G03X167717I8268J0D01*
G01D02*
G03X151181I-8268J0D01*
G01D02*
G03X167717I8268J0D01*
G01D02*
G03X151181I-8268J0D01*
G01X177166Y631102D02*
Y685039D01*
G01X173229Y627165D02*
G03X177166Y631102I0J3937D01*
G01Y685039D02*
G03X173229Y688976I-3937J0D01*
G01X211024Y646850D02*
G03X194489I-8267J0D01*
G01D02*
G03X211024I8267J0D01*
G01D02*
G03X194489I-8267J0D01*
G01D02*
G03X211024I8267J0D01*
G01D02*
G03X194489I-8267J0D01*
G01D02*
G03X211024I8267J0D01*
G01D02*
G03X194489I-8267J0D01*
G01D02*
G03X211024I8267J0D01*
G01X194489D02*
G03X211024I8267J0D01*
G01D02*
G03X194489I-8267J0D01*
G01D02*
G03X211024I8267J0D01*
G01D02*
G03X194489I-8267J0D01*
G01X188977Y627165D02*
X358268D01*
G01X185040Y631102D02*
G03X188977Y627165I3937J0D01*
G01X185040Y685039D02*
Y631102D01*
G01X188977Y688976D02*
G03X185040Y685039I0J-3937D01*
G01X358268Y688976D02*
X188977D01*
G01X177166Y615354D02*
G03X173229Y619291I-3937J0D01*
G01X188977D02*
G03X185040Y615354I0J-3937D01*
G01X358268Y619291D02*
X188977D01*
G01X222048Y0D02*
G03Y-7874I0J-3937D01*
G01D02*
X325197D01*
G01X222048Y69685D02*
G03Y61811I0J-3937D01*
G01Y139370D02*
G03Y131496I0J-3937D01*
G01Y278740D02*
G03Y270866I0J-3937D01*
G01Y209055D02*
G03Y201181I0J-3937D01*
G01Y348425D02*
G03Y340551I0J-3937D01*
G01Y418110D02*
G03Y410236I0J-3937D01*
G01Y487795D02*
G03Y479921I0J-3937D01*
G01Y557480D02*
G03Y549606I0J-3937D01*
G01Y627165D02*
G03Y619291I0J-3937D01*
G01X370079Y18307D02*
G03X362205I-3937J0D01*
G01X350394Y0D02*
G03Y-7874I0J-3937D01*
G01X325197D02*
G03Y0I0J3937D01*
G01X350394Y-7874D02*
X381890D01*
G01X352756Y19685D02*
G03X336221I-8267J0D01*
G01D02*
G03X352756I8268J0D01*
G01D02*
G03X336221I-8267J0D01*
G01D02*
G03X352756I8268J0D01*
G01D02*
G03X336221I-8267J0D01*
G01D02*
G03X352756I8268J0D01*
G01D02*
G03X336221I-8267J0D01*
G01D02*
G03X352756I8268J0D01*
G01X336221D02*
G03X352756I8268J0D01*
G01D02*
G03X336221I-8267J0D01*
G01D02*
G03X352756I8268J0D01*
G01D02*
G03X336221I-8267J0D01*
G01X362205Y3937D02*
Y57874D01*
G01X358268Y0D02*
G03X362205Y3937I0J3937D01*
G01X370079Y87992D02*
G03X362205I-3937J0D01*
G01Y113189D02*
G03X370079I3937J0D01*
G01X362205Y43504D02*
G03X370079I3937J0D01*
G01X350394Y69685D02*
G03Y61811I0J-3937D01*
G01X325197D02*
G03Y69685I0J3937D01*
G01X352756Y89370D02*
G03X336221I-8267J0D01*
G01D02*
G03X352756I8268J0D01*
G01D02*
G03X336221I-8267J0D01*
G01D02*
G03X352756I8268J0D01*
G01D02*
G03X336221I-8267J0D01*
G01D02*
G03X352756I8268J0D01*
G01D02*
G03X336221I-8267J0D01*
G01D02*
G03X352756I8268J0D01*
G01X336221D02*
G03X352756I8268J0D01*
G01D02*
G03X336221I-8267J0D01*
G01D02*
G03X352756I8268J0D01*
G01D02*
G03X336221I-8267J0D01*
G01X362205Y73622D02*
Y127559D01*
G01X358268Y69685D02*
G03X362205Y73622I0J3937D01*
G01Y57874D02*
G03X358268Y61811I-3937J0D01*
G01X370079Y157677D02*
G03X362205I-3937J0D01*
G01Y182874D02*
G03X370079I3937J0D01*
G01X350394Y139370D02*
G03Y131496I0J-3937D01*
G01X325197D02*
G03Y139370I0J3937D01*
G01X352756Y159055D02*
G03X336221I-8267J0D01*
G01D02*
G03X352756I8268J0D01*
G01D02*
G03X336221I-8267J0D01*
G01D02*
G03X352756I8268J0D01*
G01D02*
G03X336221I-8267J0D01*
G01D02*
G03X352756I8268J0D01*
G01D02*
G03X336221I-8267J0D01*
G01D02*
G03X352756I8268J0D01*
G01X336221D02*
G03X352756I8268J0D01*
G01D02*
G03X336221I-8267J0D01*
G01D02*
G03X352756I8268J0D01*
G01D02*
G03X336221I-8267J0D01*
G01X362205Y143307D02*
Y197244D01*
G01X358268Y139370D02*
G03X362205Y143307I0J3937D01*
G01Y127559D02*
G03X358268Y131496I-3937J0D01*
G01X370079Y227362D02*
G03X362205I-3937J0D01*
G01Y252559D02*
G03X370079I3937J0D01*
G01X350394Y278740D02*
G03Y270866I0J-3937D01*
G01X325197D02*
G03Y278740I0J3937D01*
G01X350394Y209055D02*
G03Y201181I0J-3937D01*
G01X325197D02*
G03Y209055I0J3937D01*
G01X358268Y278740D02*
G03X362205Y282677I0J3937D01*
G01X352756Y228740D02*
G03X336221I-8267J0D01*
G01D02*
G03X352756I8268J0D01*
G01D02*
G03X336221I-8267J0D01*
G01D02*
G03X352756I8268J0D01*
G01D02*
G03X336221I-8267J0D01*
G01D02*
G03X352756I8268J0D01*
G01D02*
G03X336221I-8267J0D01*
G01D02*
G03X352756I8268J0D01*
G01X336221D02*
G03X352756I8268J0D01*
G01D02*
G03X336221I-8267J0D01*
G01D02*
G03X352756I8268J0D01*
G01D02*
G03X336221I-8267J0D01*
G01X362205Y212992D02*
Y266929D01*
G01X358268Y209055D02*
G03X362205Y212992I0J3937D01*
G01Y266929D02*
G03X358268Y270866I-3937J0D01*
G01X362205Y197244D02*
G03X358268Y201181I-3937J0D01*
G01X370079Y297047D02*
G03X362205I-3937J0D01*
G01Y322244D02*
G03X370079I3937J0D01*
G01X350394Y348425D02*
G03Y340551I0J-3937D01*
G01X325197D02*
G03Y348425I0J3937D01*
G01X336221Y368110D02*
G03X352756I8268J0D01*
G01X336221D02*
G03X352756I8268J0D01*
G01X336221D02*
G03X352756I8268J0D01*
G01X336221D02*
G03X352756I8268J0D01*
G01X336221D02*
G03X352756I8268J0D01*
G01X336221D02*
G03X352756I8268J0D01*
G01X362205Y352362D02*
Y406299D01*
G01X358268Y348425D02*
G03X362205Y352362I0J3937D01*
G01X352756Y298425D02*
G03X336221I-8267J0D01*
G01D02*
G03X352756I8268J0D01*
G01D02*
G03X336221I-8267J0D01*
G01D02*
G03X352756I8268J0D01*
G01D02*
G03X336221I-8267J0D01*
G01D02*
G03X352756I8268J0D01*
G01D02*
G03X336221I-8267J0D01*
G01D02*
G03X352756I8268J0D01*
G01X336221D02*
G03X352756I8268J0D01*
G01D02*
G03X336221I-8267J0D01*
G01D02*
G03X352756I8268J0D01*
G01D02*
G03X336221I-8267J0D01*
G01X362205Y282677D02*
Y336614D01*
G01D02*
G03X358268Y340551I-3937J0D01*
G01X370079Y436417D02*
G03X362205I-3937J0D01*
G01X370079Y366732D02*
G03X362205I-3937J0D01*
G01Y391929D02*
G03X370079I3937J0D01*
G01X350394Y418110D02*
G03Y410236I0J-3937D01*
G01X325197D02*
G03Y418110I0J3937D01*
G01X352756Y437795D02*
G03X336221I-8267J0D01*
G01D02*
G03X352756I8268J0D01*
G01D02*
G03X336221I-8267J0D01*
G01D02*
G03X352756I8268J0D01*
G01D02*
G03X336221I-8267J0D01*
G01D02*
G03X352756I8268J0D01*
G01D02*
G03X336221I-8267J0D01*
G01D02*
G03X352756I8268J0D01*
G01X336221D02*
G03X352756I8268J0D01*
G01D02*
G03X336221I-8267J0D01*
G01D02*
G03X352756I8268J0D01*
G01D02*
G03X336221I-8267J0D01*
G01X362205Y422047D02*
Y475984D01*
G01X358268Y418110D02*
G03X362205Y422047I0J3937D01*
G01X352756Y368110D02*
G03X336221I-8267J0D01*
G01X352756D02*
G03X336221I-8267J0D01*
G01X352756D02*
G03X336221I-8267J0D01*
G01X352756D02*
G03X336221I-8267J0D01*
G01X352756D02*
G03X336221I-8267J0D01*
G01X352756D02*
G03X336221I-8267J0D01*
G01X362205Y406299D02*
G03X358268Y410236I-3937J0D01*
G01X370079Y506102D02*
G03X362205I-3937J0D01*
G01Y531299D02*
G03X370079I3937J0D01*
G01X362205Y461614D02*
G03X370079I3937J0D01*
G01X350394Y487795D02*
G03Y479921I0J-3937D01*
G01X325197D02*
G03Y487795I0J3937D01*
G01X352756Y507480D02*
G03X336221I-8267J0D01*
G01D02*
G03X352756I8268J0D01*
G01D02*
G03X336221I-8267J0D01*
G01D02*
G03X352756I8268J0D01*
G01D02*
G03X336221I-8267J0D01*
G01D02*
G03X352756I8268J0D01*
G01D02*
G03X336221I-8267J0D01*
G01D02*
G03X352756I8268J0D01*
G01X336221D02*
G03X352756I8268J0D01*
G01D02*
G03X336221I-8267J0D01*
G01D02*
G03X352756I8268J0D01*
G01D02*
G03X336221I-8267J0D01*
G01X362205Y491732D02*
Y545669D01*
G01X358268Y487795D02*
G03X362205Y491732I0J3937D01*
G01Y475984D02*
G03X358268Y479921I-3937J0D01*
G01X370079Y575787D02*
G03X362205I-3937J0D01*
G01Y600984D02*
G03X370079I3937J0D01*
G01X350394Y557480D02*
G03Y549606I0J-3937D01*
G01X325197D02*
G03Y557480I0J3937D01*
G01X352756Y577165D02*
G03X336221I-8267J0D01*
G01D02*
G03X352756I8268J0D01*
G01D02*
G03X336221I-8267J0D01*
G01D02*
G03X352756I8268J0D01*
G01D02*
G03X336221I-8267J0D01*
G01D02*
G03X352756I8268J0D01*
G01D02*
G03X336221I-8267J0D01*
G01D02*
G03X352756I8268J0D01*
G01X336221D02*
G03X352756I8268J0D01*
G01D02*
G03X336221I-8267J0D01*
G01D02*
G03X352756I8268J0D01*
G01D02*
G03X336221I-8267J0D01*
G01X362205Y561417D02*
Y615354D01*
G01X358268Y557480D02*
G03X362205Y561417I0J3937D01*
G01Y545669D02*
G03X358268Y549606I-3937J0D01*
G01X370079Y645472D02*
G03X362205I-3937J0D01*
G01Y670669D02*
G03X370079I3937J0D01*
G01X350394Y627165D02*
G03Y619291I0J-3937D01*
G01X325197D02*
G03Y627165I0J3937D01*
G01X352756Y646850D02*
G03X336221I-8267J0D01*
G01D02*
G03X352756I8268J0D01*
G01D02*
G03X336221I-8267J0D01*
G01D02*
G03X352756I8268J0D01*
G01D02*
G03X336221I-8267J0D01*
G01D02*
G03X352756I8268J0D01*
G01D02*
G03X336221I-8267J0D01*
G01D02*
G03X352756I8268J0D01*
G01X336221D02*
G03X352756I8268J0D01*
G01D02*
G03X336221I-8267J0D01*
G01D02*
G03X352756I8268J0D01*
G01D02*
G03X336221I-8267J0D01*
G01X362205Y631102D02*
Y685039D01*
G01X358268Y627165D02*
G03X362205Y631102I0J3937D01*
G01Y685039D02*
G03X358268Y688976I-3937J0D01*
G01X362205Y615354D02*
G03X358268Y619291I-3937J0D01*
G01X407087Y0D02*
G03Y-7874I0J-3937D01*
G01X381890D02*
G03Y0I0J3937D01*
G01X407087Y-7874D02*
X510237D01*
G01X396063Y19685D02*
G03X379528I-8268J0D01*
G01D02*
G03X396063I8267J0D01*
G01D02*
G03X379528I-8268J0D01*
G01D02*
G03X396063I8267J0D01*
G01D02*
G03X379528I-8268J0D01*
G01D02*
G03X396063I8267J0D01*
G01D02*
G03X379528I-8268J0D01*
G01D02*
G03X396063I8267J0D01*
G01X379528D02*
G03X396063I8267J0D01*
G01D02*
G03X379528I-8268J0D01*
G01D02*
G03X396063I8267J0D01*
G01D02*
G03X379528I-8268J0D01*
G01X374016Y0D02*
X543307D01*
G01X370079Y3937D02*
G03X374016Y0I3937J0D01*
G01X370079Y57874D02*
Y3937D01*
G01X407087Y69685D02*
G03Y61811I0J-3937D01*
G01X381890D02*
G03Y69685I0J3937D01*
G01X396063Y89370D02*
G03X379528I-8268J0D01*
G01D02*
G03X396063I8267J0D01*
G01D02*
G03X379528I-8268J0D01*
G01D02*
G03X396063I8267J0D01*
G01D02*
G03X379528I-8268J0D01*
G01D02*
G03X396063I8267J0D01*
G01D02*
G03X379528I-8268J0D01*
G01D02*
G03X396063I8267J0D01*
G01X379528D02*
G03X396063I8267J0D01*
G01D02*
G03X379528I-8268J0D01*
G01D02*
G03X396063I8267J0D01*
G01D02*
G03X379528I-8268J0D01*
G01X374016Y69685D02*
X543307D01*
G01X370079Y73622D02*
G03X374016Y69685I3937J0D01*
G01X370079Y127559D02*
Y73622D01*
G01X374016Y61811D02*
G03X370079Y57874I0J-3937D01*
G01X543307Y61811D02*
X374016D01*
G01X407087Y139370D02*
G03Y131496I0J-3937D01*
G01X381890D02*
G03Y139370I0J3937D01*
G01X396063Y159055D02*
G03X379528I-8268J0D01*
G01D02*
G03X396063I8267J0D01*
G01D02*
G03X379528I-8268J0D01*
G01D02*
G03X396063I8267J0D01*
G01D02*
G03X379528I-8268J0D01*
G01D02*
G03X396063I8267J0D01*
G01D02*
G03X379528I-8268J0D01*
G01D02*
G03X396063I8267J0D01*
G01X379528D02*
G03X396063I8267J0D01*
G01D02*
G03X379528I-8268J0D01*
G01D02*
G03X396063I8267J0D01*
G01D02*
G03X379528I-8268J0D01*
G01X374016Y139370D02*
X543307D01*
G01X370079Y143307D02*
G03X374016Y139370I3937J0D01*
G01X370079Y197244D02*
Y143307D01*
G01X374016Y131496D02*
G03X370079Y127559I0J-3937D01*
G01X543307Y131496D02*
X374016D01*
G01X407087Y278740D02*
G03Y270866I0J-3937D01*
G01X381890D02*
G03Y278740I0J3937D01*
G01X407087Y209055D02*
G03Y201181I0J-3937D01*
G01X381890D02*
G03Y209055I0J3937D01*
G01X374016Y278740D02*
X543307D01*
G01X370079Y282677D02*
G03X374016Y278740I3937J0D01*
G01X396063Y228740D02*
G03X379528I-8268J0D01*
G01D02*
G03X396063I8267J0D01*
G01D02*
G03X379528I-8268J0D01*
G01D02*
G03X396063I8267J0D01*
G01D02*
G03X379528I-8268J0D01*
G01D02*
G03X396063I8267J0D01*
G01D02*
G03X379528I-8268J0D01*
G01D02*
G03X396063I8267J0D01*
G01X379528D02*
G03X396063I8267J0D01*
G01D02*
G03X379528I-8268J0D01*
G01D02*
G03X396063I8267J0D01*
G01D02*
G03X379528I-8268J0D01*
G01X374016Y209055D02*
X543307D01*
G01X370079Y212992D02*
G03X374016Y209055I3937J0D01*
G01X370079Y266929D02*
Y212992D01*
G01X374016Y270866D02*
G03X370079Y266929I0J-3937D01*
G01X543307Y270866D02*
X374016D01*
G01Y201181D02*
G03X370079Y197244I0J-3937D01*
G01X543307Y201181D02*
X374016D01*
G01X407087Y348425D02*
G03Y340551I0J-3937D01*
G01X381890D02*
G03Y348425I0J3937D01*
G01X379528Y368110D02*
G03X396063I8267J0D01*
G01X379528D02*
G03X396063I8267J0D01*
G01X379528D02*
G03X396063I8267J0D01*
G01X379528D02*
G03X396063I8267J0D01*
G01X379528D02*
G03X396063I8267J0D01*
G01X379528D02*
G03X396063I8267J0D01*
G01X374016Y348425D02*
X543307D01*
G01X370079Y352362D02*
G03X374016Y348425I3937J0D01*
G01X370079Y406299D02*
Y352362D01*
G01X396063Y298425D02*
G03X379528I-8268J0D01*
G01D02*
G03X396063I8267J0D01*
G01D02*
G03X379528I-8268J0D01*
G01D02*
G03X396063I8267J0D01*
G01D02*
G03X379528I-8268J0D01*
G01D02*
G03X396063I8267J0D01*
G01D02*
G03X379528I-8268J0D01*
G01D02*
G03X396063I8267J0D01*
G01X379528D02*
G03X396063I8267J0D01*
G01D02*
G03X379528I-8268J0D01*
G01D02*
G03X396063I8267J0D01*
G01D02*
G03X379528I-8268J0D01*
G01X370079Y336614D02*
Y282677D01*
G01X374016Y340551D02*
G03X370079Y336614I0J-3937D01*
G01X543307Y340551D02*
X374016D01*
G01X407087Y418110D02*
G03Y410236I0J-3937D01*
G01X381890D02*
G03Y418110I0J3937D01*
G01X396063Y437795D02*
G03X379528I-8268J0D01*
G01D02*
G03X396063I8267J0D01*
G01D02*
G03X379528I-8268J0D01*
G01D02*
G03X396063I8267J0D01*
G01D02*
G03X379528I-8268J0D01*
G01D02*
G03X396063I8267J0D01*
G01D02*
G03X379528I-8268J0D01*
G01D02*
G03X396063I8267J0D01*
G01X379528D02*
G03X396063I8267J0D01*
G01D02*
G03X379528I-8268J0D01*
G01D02*
G03X396063I8267J0D01*
G01D02*
G03X379528I-8268J0D01*
G01X374016Y418110D02*
X543307D01*
G01X370079Y422047D02*
G03X374016Y418110I3937J0D01*
G01X370079Y475984D02*
Y422047D01*
G01X396063Y368110D02*
G03X379528I-8268J0D01*
G01X396063D02*
G03X379528I-8268J0D01*
G01X396063D02*
G03X379528I-8268J0D01*
G01X396063D02*
G03X379528I-8268J0D01*
G01X396063D02*
G03X379528I-8268J0D01*
G01X396063D02*
G03X379528I-8268J0D01*
G01X374016Y410236D02*
G03X370079Y406299I0J-3937D01*
G01X543307Y410236D02*
X374016D01*
G01X407087Y487795D02*
G03Y479921I0J-3937D01*
G01X381890D02*
G03Y487795I0J3937D01*
G01X396063Y507480D02*
G03X379528I-8268J0D01*
G01D02*
G03X396063I8267J0D01*
G01D02*
G03X379528I-8268J0D01*
G01D02*
G03X396063I8267J0D01*
G01D02*
G03X379528I-8268J0D01*
G01D02*
G03X396063I8267J0D01*
G01D02*
G03X379528I-8268J0D01*
G01D02*
G03X396063I8267J0D01*
G01X379528D02*
G03X396063I8267J0D01*
G01D02*
G03X379528I-8268J0D01*
G01D02*
G03X396063I8267J0D01*
G01D02*
G03X379528I-8268J0D01*
G01X374016Y487795D02*
X543307D01*
G01X370079Y491732D02*
G03X374016Y487795I3937J0D01*
G01X370079Y545669D02*
Y491732D01*
G01X374016Y479921D02*
G03X370079Y475984I0J-3937D01*
G01X543307Y479921D02*
X374016D01*
G01X407087Y557480D02*
G03Y549606I0J-3937D01*
G01X381890D02*
G03Y557480I0J3937D01*
G01X396063Y577165D02*
G03X379528I-8268J0D01*
G01D02*
G03X396063I8267J0D01*
G01D02*
G03X379528I-8268J0D01*
G01D02*
G03X396063I8267J0D01*
G01D02*
G03X379528I-8268J0D01*
G01D02*
G03X396063I8267J0D01*
G01D02*
G03X379528I-8268J0D01*
G01D02*
G03X396063I8267J0D01*
G01X379528D02*
G03X396063I8267J0D01*
G01D02*
G03X379528I-8268J0D01*
G01D02*
G03X396063I8267J0D01*
G01D02*
G03X379528I-8268J0D01*
G01X374016Y557480D02*
X543307D01*
G01X370079Y561417D02*
G03X374016Y557480I3937J0D01*
G01X370079Y615354D02*
Y561417D01*
G01X374016Y549606D02*
G03X370079Y545669I0J-3937D01*
G01X543307Y549606D02*
X374016D01*
G01X407087Y627165D02*
G03Y619291I0J-3937D01*
G01X381890D02*
G03Y627165I0J3937D01*
G01X396063Y646850D02*
G03X379528I-8268J0D01*
G01D02*
G03X396063I8267J0D01*
G01D02*
G03X379528I-8268J0D01*
G01D02*
G03X396063I8267J0D01*
G01D02*
G03X379528I-8268J0D01*
G01D02*
G03X396063I8267J0D01*
G01D02*
G03X379528I-8268J0D01*
G01D02*
G03X396063I8267J0D01*
G01X379528D02*
G03X396063I8267J0D01*
G01D02*
G03X379528I-8268J0D01*
G01D02*
G03X396063I8267J0D01*
G01D02*
G03X379528I-8268J0D01*
G01X374016Y627165D02*
X543307D01*
G01X370079Y631102D02*
G03X374016Y627165I3937J0D01*
G01X370079Y685039D02*
Y631102D01*
G01X374016Y688976D02*
G03X370079Y685039I0J-3937D01*
G01X543307Y688976D02*
X374016D01*
G01Y619291D02*
G03X370079Y615354I0J-3937D01*
G01X543307Y619291D02*
X374016D01*
G01X510237Y-7874D02*
G03Y0I0J3937D01*
G01X537796Y19685D02*
G03X521260I-8268J0D01*
G01D02*
G03X537796I8268J0D01*
G01D02*
G03X521260I-8268J0D01*
G01D02*
G03X537796I8268J0D01*
G01D02*
G03X521260I-8268J0D01*
G01D02*
G03X537796I8268J0D01*
G01D02*
G03X521260I-8268J0D01*
G01D02*
G03X537796I8268J0D01*
G01X521260D02*
G03X537796I8268J0D01*
G01D02*
G03X521260I-8268J0D01*
G01D02*
G03X537796I8268J0D01*
G01D02*
G03X521260I-8268J0D01*
G01X510237Y61811D02*
G03Y69685I0J3937D01*
G01X537796Y89370D02*
G03X521260I-8268J0D01*
G01D02*
G03X537796I8268J0D01*
G01D02*
G03X521260I-8268J0D01*
G01D02*
G03X537796I8268J0D01*
G01D02*
G03X521260I-8268J0D01*
G01D02*
G03X537796I8268J0D01*
G01D02*
G03X521260I-8268J0D01*
G01D02*
G03X537796I8268J0D01*
G01X521260D02*
G03X537796I8268J0D01*
G01D02*
G03X521260I-8268J0D01*
G01D02*
G03X537796I8268J0D01*
G01D02*
G03X521260I-8268J0D01*
G01X510237Y131496D02*
G03Y139370I0J3937D01*
G01X537796Y159055D02*
G03X521260I-8268J0D01*
G01D02*
G03X537796I8268J0D01*
G01D02*
G03X521260I-8268J0D01*
G01D02*
G03X537796I8268J0D01*
G01D02*
G03X521260I-8268J0D01*
G01D02*
G03X537796I8268J0D01*
G01D02*
G03X521260I-8268J0D01*
G01D02*
G03X537796I8268J0D01*
G01X521260D02*
G03X537796I8268J0D01*
G01D02*
G03X521260I-8268J0D01*
G01D02*
G03X537796I8268J0D01*
G01D02*
G03X521260I-8268J0D01*
G01X510237Y270866D02*
G03Y278740I0J3937D01*
G01Y201181D02*
G03Y209055I0J3937D01*
G01X537796Y228740D02*
G03X521260I-8268J0D01*
G01D02*
G03X537796I8268J0D01*
G01D02*
G03X521260I-8268J0D01*
G01D02*
G03X537796I8268J0D01*
G01D02*
G03X521260I-8268J0D01*
G01D02*
G03X537796I8268J0D01*
G01D02*
G03X521260I-8268J0D01*
G01D02*
G03X537796I8268J0D01*
G01X521260D02*
G03X537796I8268J0D01*
G01D02*
G03X521260I-8268J0D01*
G01D02*
G03X537796I8268J0D01*
G01D02*
G03X521260I-8268J0D01*
G01X510237Y340551D02*
G03Y348425I0J3937D01*
G01X521260Y368110D02*
G03X537796I8268J0D01*
G01X521260D02*
G03X537796I8268J0D01*
G01X521260D02*
G03X537796I8268J0D01*
G01X521260D02*
G03X537796I8268J0D01*
G01X521260D02*
G03X537796I8268J0D01*
G01X521260D02*
G03X537796I8268J0D01*
G01Y298425D02*
G03X521260I-8268J0D01*
G01D02*
G03X537796I8268J0D01*
G01D02*
G03X521260I-8268J0D01*
G01D02*
G03X537796I8268J0D01*
G01D02*
G03X521260I-8268J0D01*
G01D02*
G03X537796I8268J0D01*
G01D02*
G03X521260I-8268J0D01*
G01D02*
G03X537796I8268J0D01*
G01X521260D02*
G03X537796I8268J0D01*
G01D02*
G03X521260I-8268J0D01*
G01D02*
G03X537796I8268J0D01*
G01D02*
G03X521260I-8268J0D01*
G01X510237Y410236D02*
G03Y418110I0J3937D01*
G01X537796Y437795D02*
G03X521260I-8268J0D01*
G01D02*
G03X537796I8268J0D01*
G01D02*
G03X521260I-8268J0D01*
G01D02*
G03X537796I8268J0D01*
G01D02*
G03X521260I-8268J0D01*
G01D02*
G03X537796I8268J0D01*
G01D02*
G03X521260I-8268J0D01*
G01D02*
G03X537796I8268J0D01*
G01X521260D02*
G03X537796I8268J0D01*
G01D02*
G03X521260I-8268J0D01*
G01D02*
G03X537796I8268J0D01*
G01D02*
G03X521260I-8268J0D01*
G01X537796Y368110D02*
G03X521260I-8268J0D01*
G01X537796D02*
G03X521260I-8268J0D01*
G01X537796D02*
G03X521260I-8268J0D01*
G01X537796D02*
G03X521260I-8268J0D01*
G01X537796D02*
G03X521260I-8268J0D01*
G01X537796D02*
G03X521260I-8268J0D01*
G01X510237Y479921D02*
G03Y487795I0J3937D01*
G01X537796Y507480D02*
G03X521260I-8268J0D01*
G01D02*
G03X537796I8268J0D01*
G01D02*
G03X521260I-8268J0D01*
G01D02*
G03X537796I8268J0D01*
G01D02*
G03X521260I-8268J0D01*
G01D02*
G03X537796I8268J0D01*
G01D02*
G03X521260I-8268J0D01*
G01D02*
G03X537796I8268J0D01*
G01X521260D02*
G03X537796I8268J0D01*
G01D02*
G03X521260I-8268J0D01*
G01D02*
G03X537796I8268J0D01*
G01D02*
G03X521260I-8268J0D01*
G01X510237Y549606D02*
G03Y557480I0J3937D01*
G01X537796Y577165D02*
G03X521260I-8268J0D01*
G01D02*
G03X537796I8268J0D01*
G01D02*
G03X521260I-8268J0D01*
G01D02*
G03X537796I8268J0D01*
G01D02*
G03X521260I-8268J0D01*
G01D02*
G03X537796I8268J0D01*
G01D02*
G03X521260I-8268J0D01*
G01D02*
G03X537796I8268J0D01*
G01X521260D02*
G03X537796I8268J0D01*
G01D02*
G03X521260I-8268J0D01*
G01D02*
G03X537796I8268J0D01*
G01D02*
G03X521260I-8268J0D01*
G01X510237Y619291D02*
G03Y627165I0J3937D01*
G01X537796Y646850D02*
G03X521260I-8268J0D01*
G01D02*
G03X537796I8268J0D01*
G01D02*
G03X521260I-8268J0D01*
G01D02*
G03X537796I8268J0D01*
G01D02*
G03X521260I-8268J0D01*
G01D02*
G03X537796I8268J0D01*
G01D02*
G03X521260I-8268J0D01*
G01D02*
G03X537796I8268J0D01*
G01X521260D02*
G03X537796I8268J0D01*
G01D02*
G03X521260I-8268J0D01*
G01D02*
G03X537796I8268J0D01*
G01D02*
G03X521260I-8268J0D01*
G01X539370Y-19685D02*
G03X547244Y-11811I0J7874D01*
G01X535433Y0D02*
G03Y-7874I0J-3937D01*
G01X547244D02*
Y-11811D01*
G01X535433Y-7874D02*
X547244D01*
G01Y3937D02*
Y57874D01*
G01X543307Y0D02*
G03X547244Y3937I0J3937D01*
G01X535433Y69685D02*
G03Y61811I0J-3937D01*
G01X547244Y73622D02*
Y127559D01*
G01X543307Y69685D02*
G03X547244Y73622I0J3937D01*
G01Y57874D02*
G03X543307Y61811I-3937J0D01*
G01X535433Y139370D02*
G03Y131496I0J-3937D01*
G01X547244Y143307D02*
Y197244D01*
G01X543307Y139370D02*
G03X547244Y143307I0J3937D01*
G01Y127559D02*
G03X543307Y131496I-3937J0D01*
G01X535433Y278740D02*
G03Y270866I0J-3937D01*
G01Y209055D02*
G03Y201181I0J-3937D01*
G01X543307Y278740D02*
G03X547244Y282677I0J3937D01*
G01Y212992D02*
Y266929D01*
G01X543307Y209055D02*
G03X547244Y212992I0J3937D01*
G01Y266929D02*
G03X543307Y270866I-3937J0D01*
G01X547244Y197244D02*
G03X543307Y201181I-3937J0D01*
G01X535433Y348425D02*
G03Y340551I0J-3937D01*
G01X547244Y352362D02*
Y406299D01*
G01X543307Y348425D02*
G03X547244Y352362I0J3937D01*
G01Y282677D02*
Y336614D01*
G01D02*
G03X543307Y340551I-3937J0D01*
G01X535433Y418110D02*
G03Y410236I0J-3937D01*
G01X547244Y422047D02*
Y475984D01*
G01X543307Y418110D02*
G03X547244Y422047I0J3937D01*
G01Y406299D02*
G03X543307Y410236I-3937J0D01*
G01X535433Y487795D02*
G03Y479921I0J-3937D01*
G01X547244Y491732D02*
Y545669D01*
G01X543307Y487795D02*
G03X547244Y491732I0J3937D01*
G01Y475984D02*
G03X543307Y479921I-3937J0D01*
G01X535433Y557480D02*
G03Y549606I0J-3937D01*
G01X547244Y561417D02*
Y615354D01*
G01X543307Y557480D02*
G03X547244Y561417I0J3937D01*
G01Y545669D02*
G03X543307Y549606I-3937J0D01*
G01X535433Y627165D02*
G03Y619291I0J-3937D01*
G01X547244Y631102D02*
Y685039D01*
G01X543307Y627165D02*
G03X547244Y631102I0J3937D01*
G01Y685039D02*
G03X543307Y688976I-3937J0D01*
G01X547244Y615354D02*
G03X543307Y619291I-3937J0D01*
G54D15*
X62200Y25000D03*
X105200Y21000D03*
X62700D03*
X104700Y29500D03*
X57700Y29000D03*
X83200Y37500D03*
G54D24*
X36930Y38484D03*
X41654D03*
X46378D03*
Y55414D03*
X41654D03*
X36930D03*
G54D25*
X83500Y33200D03*
X133500Y22200D03*
G54D16*
X58800Y25000D03*
X101800Y21000D03*
X59300D03*
X101300Y29500D03*
X54300Y29000D03*
X79800Y37500D03*
G54D17*
X83500Y29800D03*
X133500Y18800D03*
G54D26*
X71000Y50200D03*
Y42800D03*
G54D27*
X89000Y49000D03*
X80000D03*
G54D18*
X101300Y25500D03*
X46300Y21000D03*
X88800D03*
X77300D03*
G54D28*
X64500Y42200D03*
G54D19*
X104700Y25500D03*
X49700Y21000D03*
X92200D03*
X80700D03*
G54D29*
X64500Y45800D03*
M02*
